# T6G (Grand Teton) — schematic netlist excerpt (pin names and nets, part order shuffled) for the footprints in the layout excerpt that follows; sources: Cadence DE-HDL packaged netlist, KiCad conversion of 04192023_DAF0TMB3IC0_F0TG_MB_C_brd_V02_OCP.brd

C2324  Q_CAP  22UF 4V 20% X6S  pkg C0402  page 73 : A = PVDDCR_CPU0_P1 ; B = GND
PR132  Q_RES  2.2 1% CHIP  pkg 0402LF  page 208 : A = PVDD11_S3_P0_PVCC ; B = PVDD11_S3_P0_VCC2

(kicad_pcb
	(version 20260206)
	(generator "pcbnew")
	(generator_version "10.0")
	(general
		(thickness 1.6)
		(legacy_teardrops no)
	)
	(paper "A4")
	(title_block
		(title "04192023_DAF0TMB3IC0_F0TG_MB_C_brd_V02_OCP.brd")
		(comment 1 "Grand Teton / footprints 7773-7774 of 8354")
	)
	(layers
		(0 "F.Cu" signal "TOP")
		(4 "In1.Cu" signal "GND")
		(6 "In2.Cu" signal "IN1")
		(8 "In3.Cu" signal "GND1")
		(10 "In4.Cu" signal "IN2")
		(12 "In5.Cu" signal "GND2")
		(14 "In6.Cu" signal "IN3")
		(16 "In7.Cu" signal "GND3")
		(18 "In8.Cu" signal "VCC")
		(20 "In9.Cu" signal "VCC1")
		(22 "In10.Cu" signal "GND4")
		(24 "In11.Cu" signal "IN4")
		(26 "In12.Cu" signal "GND5")
		(28 "In13.Cu" signal "IN5")
		(30 "In14.Cu" signal "GND6")
		(32 "In15.Cu" signal "IN6")
		(34 "In16.Cu" signal "GND7")
		(2 "B.Cu" signal "BOTTOM")
		(9 "F.Adhes" user "F.Adhesive")
		(11 "B.Adhes" user "B.Adhesive")
		(13 "F.Paste" user "Package Geometry/Pastemask Top")
		(15 "B.Paste" user "Package Geometry/Pastemask Bottom")
		(5 "F.SilkS" user "Ref Des/Silkscreen Top")
		(7 "B.SilkS" user "Ref Des/Silkscreen Bottom")
		(1 "F.Mask" user "Board Geometry/Soldermask Top")
		(3 "B.Mask" user "Board Geometry/Soldermask Bottom")
		(17 "Dwgs.User" user "User.Drawings")
		(19 "Cmts.User" user "User.Comments")
		(21 "Eco1.User" user "User.Eco1")
		(23 "Eco2.User" user "User.Eco2")
		(25 "Edge.Cuts" user "Board Geometry/Outline")
		(27 "Margin" user)
		(31 "F.CrtYd" user "Package Geometry/Place Bound Top")
		(29 "B.CrtYd" user "Package Geometry/Place Bound Bottom")
		(35 "F.Fab" user "Ref Des/Assembly Top")
		(33 "B.Fab" user "Ref Des/Assembly Bottom")
	)
	(footprint ""
		(layer "B.Cu")
		(at 429.659796 -352.199448 -90)
		(property "Reference" "PR132"
			(at 0 0 90)
			(layer "B.SilkS")
			(hide yes)
			(effects
				(font
					(size 1.27 1.27)
				)
				(justify mirror)
			)
		)
		(property "Value" ""
			(at 0 0 90)
			(layer "B.Fab")
			(effects
				(font
					(size 1.27 1.27)
				)
				(justify mirror)
			)
		)
		(duplicate_pad_numbers_are_jumpers no)
		(fp_line
			(start -0.7874 0.4064)
			(end 0.7874 0.4064)
			(stroke
				(width 0.1524)
				(type default)
			)
			(layer "B.SilkS")
		)
		(fp_line
			(start 0.7874 0.4064)
			(end 0.7874 -0.4064)
			(stroke
				(width 0.1524)
				(type default)
			)
			(layer "B.SilkS")
		)
		(fp_line
			(start -0.7874 -0.4064)
			(end -0.7874 0.4064)
			(stroke
				(width 0.1524)
				(type default)
			)
			(layer "B.SilkS")
		)
		(fp_line
			(start 0.7874 -0.4064)
			(end -0.7874 -0.4064)
			(stroke
				(width 0.1524)
				(type default)
			)
			(layer "B.SilkS")
		)
		(fp_line
			(start -0.67945 0.3048)
			(end -0.120396 0.3048)
			(stroke
				(width 0.1)
				(type default)
			)
			(layer "B.Fab")
		)
		(fp_line
			(start -0.120396 0.3048)
			(end -0.120396 0.2794)
			(stroke
				(width 0.1)
				(type default)
			)
			(layer "B.Fab")
		)
		(fp_line
			(start 0.12065 0.3048)
			(end 0.67945 0.3048)
			(stroke
				(width 0.1)
				(type default)
			)
			(layer "B.Fab")
		)
		(fp_line
			(start 0.67945 0.3048)
			(end 0.67945 -0.305054)
			(stroke
				(width 0.1)
				(type default)
			)
			(layer "B.Fab")
		)
		(fp_line
			(start -0.120396 0.2794)
			(end 0.12065 0.2794)
			(stroke
				(width 0.1)
				(type default)
			)
			(layer "B.Fab")
		)
		(fp_line
			(start 0.12065 0.2794)
			(end 0.12065 0.3048)
			(stroke
				(width 0.1)
				(type default)
			)
			(layer "B.Fab")
		)
		(fp_line
			(start -0.12065 -0.2794)
			(end -0.12065 -0.3048)
			(stroke
				(width 0.1)
				(type default)
			)
			(layer "B.Fab")
		)
		(fp_line
			(start 0.12065 -0.2794)
			(end -0.12065 -0.2794)
			(stroke
				(width 0.1)
				(type default)
			)
			(layer "B.Fab")
		)
		(fp_line
			(start -0.67945 -0.3048)
			(end -0.67945 0.3048)
			(stroke
				(width 0.1)
				(type default)
			)
			(layer "B.Fab")
		)
		(fp_line
			(start -0.12065 -0.3048)
			(end -0.67945 -0.3048)
			(stroke
				(width 0.1)
				(type default)
			)
			(layer "B.Fab")
		)
		(fp_line
			(start 0.12065 -0.305054)
			(end 0.12065 -0.2794)
			(stroke
				(width 0.1)
				(type default)
			)
			(layer "B.Fab")
		)
		(fp_line
			(start 0.67945 -0.305054)
			(end 0.12065 -0.305054)
			(stroke
				(width 0.1)
				(type default)
			)
			(layer "B.Fab")
		)
		(pad "1" smd circle
			(at 0.40005 0 90)
			(size 0 0)
			(layers "B.Cu" "B.Mask" "B.Paste")
			(net "PVDD11_S3_P0_PVCC")
		)
		(pad "2" smd circle
			(at -0.40005 0 90)
			(size 0 0)
			(layers "B.Cu" "B.Mask" "B.Paste")
			(net "PVDD11_S3_P0_VCC2")
		)
	)
	(footprint ""
		(layer "B.Cu")
		(at 115.130834 -246.376952 180)
		(property "Reference" "C2324"
			(at 0 0 0)
			(layer "B.SilkS")
			(hide yes)
			(effects
				(font
					(size 1.27 1.27)
				)
				(justify mirror)
			)
		)
		(property "Value" ""
			(at 0 0 0)
			(layer "B.Fab")
			(effects
				(font
					(size 1.27 1.27)
				)
				(justify mirror)
			)
		)
		(duplicate_pad_numbers_are_jumpers no)
		(fp_line
			(start 0.7874 0.4064)
			(end 0.7874 -0.4064)
			(stroke
				(width 0.1524)
				(type default)
			)
			(layer "B.SilkS")
		)
		(fp_line
			(start 0.7874 -0.4064)
			(end -0.7874 -0.4064)
			(stroke
				(width 0.1524)
				(type default)
			)
			(layer "B.SilkS")
		)
		(fp_line
			(start -0.7874 0.4064)
			(end 0.7874 0.4064)
			(stroke
				(width 0.1524)
				(type default)
			)
			(layer "B.SilkS")
		)
		(fp_line
			(start -0.7874 -0.4064)
			(end -0.7874 0.4064)
			(stroke
				(width 0.1524)
				(type default)
			)
			(layer "B.SilkS")
		)
		(fp_line
			(start 0.67945 0.3048)
			(end 0.67945 -0.305054)
			(stroke
				(width 0.1)
				(type default)
			)
			(layer "B.Fab")
		)
		(fp_line
			(start 0.67945 -0.305054)
			(end 0.12065 -0.305054)
			(stroke
				(width 0.1)
				(type default)
			)
			(layer "B.Fab")
		)
		(fp_line
			(start 0.12065 0.3048)
			(end 0.67945 0.3048)
			(stroke
				(width 0.1)
				(type default)
			)
			(layer "B.Fab")
		)
		(fp_line
			(start 0.12065 0.2794)
			(end 0.12065 0.3048)
			(stroke
				(width 0.1)
				(type default)
			)
			(layer "B.Fab")
		)
		(fp_line
			(start 0.12065 -0.2794)
			(end -0.12065 -0.2794)
			(stroke
				(width 0.1)
				(type default)
			)
			(layer "B.Fab")
		)
		(fp_line
			(start 0.12065 -0.305054)
			(end 0.12065 -0.2794)
			(stroke
				(width 0.1)
				(type default)
			)
			(layer "B.Fab")
		)
		(fp_line
			(start -0.120396 0.3048)
			(end -0.120396 0.2794)
			(stroke
				(width 0.1)
				(type default)
			)
			(layer "B.Fab")
		)
		(fp_line
			(start -0.120396 0.2794)
			(end 0.12065 0.2794)
			(stroke
				(width 0.1)
				(type default)
			)
			(layer "B.Fab")
		)
		(fp_line
			(start -0.12065 -0.2794)
			(end -0.12065 -0.3048)
			(stroke
				(width 0.1)
				(type default)
			)
			(layer "B.Fab")
		)
		(fp_line
			(start -0.12065 -0.3048)
			(end -0.67945 -0.3048)
			(stroke
				(width 0.1)
				(type default)
			)
			(layer "B.Fab")
		)
		(fp_line
			(start -0.67945 0.3048)
			(end -0.120396 0.3048)
			(stroke
				(width 0.1)
				(type default)
			)
			(layer "B.Fab")
		)
		(fp_line
			(start -0.67945 -0.3048)
			(end -0.67945 0.3048)
			(stroke
				(width 0.1)
				(type default)
			)
			(layer "B.Fab")
		)
		(pad "1" smd circle
			(at 0.40005 0)
			(size 0 0)
			(layers "B.Cu" "B.Mask" "B.Paste")
			(net "PVDDCR_CPU0_P1")
		)
		(pad "2" smd circle
			(at -0.40005 0)
			(size 0 0)
			(layers "B.Cu" "B.Mask" "B.Paste")
			(net "GND")
		)
	)
)
